# S9S_MB_2U (Grand Teton) — schematic netlist excerpt (pin names and nets, part order shuffled) for the footprints in the layout excerpt that follows; sources: Cadence DE-HDL packaged netlist, KiCad conversion of 03242023_DA0F0TMBIJ0_F0T_Motherboard_J_brd_V01_OCP.brd

PU29  RAA229126GNPHA0  RAA229126GNP#HA0 IC  pkg QFN48_THXT  page 284
  PWM0  = PVCCFA_EHV_FIVRA_CPU1_PWM1
  PWM1  = PVCCFA_EHV_FIVRA_CPU1_PWM2
  PWM2  = PVCCFA_EHV_FIVRA_CPU1_PWM3
  PWM3  = PVCCFA_EHV_FIVRA_CPU1_PWM4
  PWM4  = PVCCIN_CPU1_PWM8
  PWM5  = PVCCIN_CPU1_PWM7
  PWM6  = PVCCIN_CPU1_PWM6
  PWM7  = PVCCIN_CPU1_PWM5
  PWM8  = PVCCIN_CPU1_PWM4
  PWM9  = PVCCIN_CPU1_PWM3
  PWM10  = PVCCIN_CPU1_PWM2
  PWM11  = PVCCIN_CPU1_PWM1
  PMSDA  = SMB_DIO_PVCCIN_CPU1
  PMSCL  = SMB_CLK_PVCCIN_CPU1
  NPMALERT  = NC_PVCCIN_CPU1_SMB_ALERT
  PG0  = PWRGD_PVCCIN_CPU1_R
  EN0  = PVCCIN_CPU1_EN_R
  NVRHOT  = IRQ_PVCCIN_CPU1_VRHOT_N
  \npinalert||npsys_crit\  = PVCCIN_CPU1_PIN_ALERT
  PG1  = PWRGD_PVCCFA_EHV_FIVRA_CPU1_R
  SVCLK  = SVID_CLK_PVCCIN_CPU1_R
  SVDATA  = SVID_DIO_PVCCIN_CPU1_R
  NSVALERT  = SVID_ALERT_PVCCIN_CPU1_R
  EN1  = PVCCFA_EHV_FIVRA_CPU1_EN_R
  VSEN0  = SH_PVCCIN_CPU1_R
  RGND0  = VSENSE_PVCCIN_CPU1_DN
  CS11  = PVCCIN_CPU1_IMON1
  CS10  = PVCCIN_CPU1_IMON2
  CS9  = PVCCIN_CPU1_IMON3
  CS8  = PVCCIN_CPU1_IMON4
  CS7  = PVCCIN_CPU1_IMON5
  CS6  = PVCCIN_CPU1_IMON6
  CS5  = PVCCIN_CPU1_IMON7
  CS4  = PVCCIN_CPU1_IMON8
  CS3  = PVCCFA_EHV_FIVRA_CPU1_IMON4
  CS2  = PVCCFA_EHV_FIVRA_CPU1_IMON3
  CS1  = PVCCFA_EHV_FIVRA_CPU1_IMON2
  CS0  = PVCCFA_EHV_FIVRA_CPU1_IMON1
  RGND1  = VSENSE_PVCCFA_EHV_FIVRA_CPU1_DN
  VSEN1  = SH_PVCCFA_EHV_FIVRA_CPU1_R
  CFP  = PVCCIN_CPU1_VR_FAULT
  ADDR_CFG  = PVCCIN_CPU1_ADDR
  TEMP0  = PVCCIN_CPU1_ATSEN
  \temp1||isys\  = PVCCFA_EHV_FIVRA_CPU1_BTSEN
  \vmon||iinsen||vsys||isys\  = PVCCIN_CPU1_CSPIN
  \vinsen||vsys\  = PVCCIN_CPU1_VIN_CSNIN
  VCC  = PVCCIN_CPU1_VCC
  VCCS  = PVCCIN_CPU1_VREF
  TH_GND  = GND

(kicad_pcb
	(version 20260206)
	(generator "pcbnew")
	(generator_version "10.0")
	(general
		(thickness 1.6)
		(legacy_teardrops no)
	)
	(paper "A4")
	(title_block
		(title "03242023_DA0F0TMBIJ0_F0T_Motherboard_J_brd_V01_OCP.brd")
		(comment 1 "Grand Teton / footprint 2465 of 6105 (PU29), pads 1-42 of 49")
	)
	(layers
		(0 "F.Cu" signal "TOP")
		(4 "In1.Cu" signal "GND")
		(6 "In2.Cu" signal "IN1")
		(8 "In3.Cu" signal "GND1")
		(10 "In4.Cu" signal "IN2")
		(12 "In5.Cu" signal "GND2")
		(14 "In6.Cu" signal "IN3")
		(16 "In7.Cu" signal "GND3")
		(18 "In8.Cu" signal "VCC")
		(20 "In9.Cu" signal "VCC1")
		(22 "In10.Cu" signal "GND4")
		(24 "In11.Cu" signal "IN4")
		(26 "In12.Cu" signal "GND5")
		(28 "In13.Cu" signal "IN5")
		(30 "In14.Cu" signal "GND6")
		(32 "In15.Cu" signal "IN6")
		(34 "In16.Cu" signal "GND7")
		(2 "B.Cu" signal "BOTTOM")
		(9 "F.Adhes" user "F.Adhesive")
		(11 "B.Adhes" user "B.Adhesive")
		(13 "F.Paste" user "Package Geometry/Pastemask Top")
		(15 "B.Paste" user "Package Geometry/Pastemask Bottom")
		(5 "F.SilkS" user "Ref Des/Silkscreen Top")
		(7 "B.SilkS" user "Ref Des/Silkscreen Bottom")
		(1 "F.Mask" user "Board Geometry/Soldermask Top")
		(3 "B.Mask" user "Board Geometry/Soldermask Bottom")
		(17 "Dwgs.User" user "User.Drawings")
		(19 "Cmts.User" user "User.Comments")
		(21 "Eco1.User" user "User.Eco1")
		(23 "Eco2.User" user "User.Eco2")
		(25 "Edge.Cuts" user "Board Geometry/Outline")
		(27 "Margin" user)
		(31 "F.CrtYd" user "Package Geometry/Place Bound Top")
		(29 "B.CrtYd" user "Package Geometry/Place Bound Bottom")
		(35 "F.Fab" user "Ref Des/Assembly Top")
		(33 "B.Fab" user "Ref Des/Assembly Bottom")
	)
	(footprint ""
		(layer "F.Cu")
		(at 108.578396 -358.848406 -90)
		(property "Reference" "PU29"
			(at 8.473948 -1.629664 0)
			(unlocked yes)
			(layer "F.SilkS")
			(effects
				(font
					(size 0.7874 0.5842)
					(thickness 0.1524)
				)
				(justify left)
			)
		)
		(property "Value" ""
			(at 0 0 270)
			(layer "F.Fab")
			(effects
				(font
					(size 1.27 1.27)
				)
			)
		)
		(duplicate_pad_numbers_are_jumpers no)
		(pad "1" smd rect
			(at -2.875026 -2.199894)
			(size 0.1778 0.6604)
			(layers "F.Cu" "F.Mask" "F.Paste")
			(net "PVCCFA_EHV_FIVRA_CPU1_PWM1")
		)
		(pad "2" smd rect
			(at -2.875026 -1.800098)
			(size 0.1778 0.6604)
			(layers "F.Cu" "F.Mask" "F.Paste")
			(net "PVCCFA_EHV_FIVRA_CPU1_PWM2")
		)
		(pad "3" smd rect
			(at -2.875026 -1.400048)
			(size 0.1778 0.6604)
			(layers "F.Cu" "F.Mask" "F.Paste")
			(net "PVCCFA_EHV_FIVRA_CPU1_PWM3")
		)
		(pad "4" smd rect
			(at -2.875026 -0.999998)
			(size 0.1778 0.6604)
			(layers "F.Cu" "F.Mask" "F.Paste")
			(net "PVCCFA_EHV_FIVRA_CPU1_PWM4")
		)
		(pad "5" smd rect
			(at -2.875026 -0.599948)
			(size 0.1778 0.6604)
			(layers "F.Cu" "F.Mask" "F.Paste")
			(net "PVCCIN_CPU1_PWM8")
		)
		(pad "6" smd rect
			(at -2.875026 -0.199898)
			(size 0.1778 0.6604)
			(layers "F.Cu" "F.Mask" "F.Paste")
			(net "PVCCIN_CPU1_PWM7")
		)
		(pad "7" smd rect
			(at -2.875026 0.199898)
			(size 0.1778 0.6604)
			(layers "F.Cu" "F.Mask" "F.Paste")
			(net "PVCCIN_CPU1_PWM6")
		)
		(pad "8" smd rect
			(at -2.875026 0.599948)
			(size 0.1778 0.6604)
			(layers "F.Cu" "F.Mask" "F.Paste")
			(net "PVCCIN_CPU1_PWM5")
		)
		(pad "9" smd rect
			(at -2.875026 0.999998)
			(size 0.1778 0.6604)
			(layers "F.Cu" "F.Mask" "F.Paste")
			(net "PVCCIN_CPU1_PWM4")
		)
		(pad "10" smd rect
			(at -2.875026 1.400048)
			(size 0.1778 0.6604)
			(layers "F.Cu" "F.Mask" "F.Paste")
			(net "PVCCIN_CPU1_PWM3")
		)
		(pad "11" smd rect
			(at -2.875026 1.800098)
			(size 0.1778 0.6604)
			(layers "F.Cu" "F.Mask" "F.Paste")
			(net "PVCCIN_CPU1_PWM2")
		)
		(pad "12" smd rect
			(at -2.875026 2.199894)
			(size 0.1778 0.6604)
			(layers "F.Cu" "F.Mask" "F.Paste")
			(net "PVCCIN_CPU1_PWM1")
		)
		(pad "13" smd rect
			(at -2.199894 2.875026 270)
			(size 0.1778 0.6604)
			(layers "F.Cu" "F.Mask" "F.Paste")
			(net "SMB_DIO_PVCCIN_CPU1")
		)
		(pad "14" smd rect
			(at -1.800098 2.875026 270)
			(size 0.1778 0.6604)
			(layers "F.Cu" "F.Mask" "F.Paste")
			(net "SMB_CLK_PVCCIN_CPU1")
		)
		(pad "15" smd rect
			(at -1.400048 2.875026 270)
			(size 0.1778 0.6604)
			(layers "F.Cu" "F.Mask" "F.Paste")
			(net "NC_PVCCIN_CPU1_SMB_ALERT")
		)
		(pad "16" smd rect
			(at -0.999998 2.875026 270)
			(size 0.1778 0.6604)
			(layers "F.Cu" "F.Mask" "F.Paste")
			(net "PWRGD_PVCCIN_CPU1_R")
		)
		(pad "17" smd rect
			(at -0.599948 2.875026 270)
			(size 0.1778 0.6604)
			(layers "F.Cu" "F.Mask" "F.Paste")
			(net "PVCCIN_CPU1_EN_R")
		)
		(pad "18" smd rect
			(at -0.199898 2.875026 270)
			(size 0.1778 0.6604)
			(layers "F.Cu" "F.Mask" "F.Paste")
			(net "IRQ_PVCCIN_CPU1_VRHOT_N")
		)
		(pad "19" smd rect
			(at 0.199898 2.875026 270)
			(size 0.1778 0.6604)
			(layers "F.Cu" "F.Mask" "F.Paste")
			(net "PVCCIN_CPU1_PIN_ALERT")
		)
		(pad "20" smd rect
			(at 0.599948 2.875026 270)
			(size 0.1778 0.6604)
			(layers "F.Cu" "F.Mask" "F.Paste")
			(net "PWRGD_PVCCFA_EHV_FIVRA_CPU1_R")
		)
		(pad "21" smd rect
			(at 0.999998 2.875026 270)
			(size 0.1778 0.6604)
			(layers "F.Cu" "F.Mask" "F.Paste")
			(net "SVID_CLK_PVCCIN_CPU1_R")
		)
		(pad "22" smd rect
			(at 1.400048 2.875026 270)
			(size 0.1778 0.6604)
			(layers "F.Cu" "F.Mask" "F.Paste")
			(net "SVID_DIO_PVCCIN_CPU1_R")
		)
		(pad "23" smd rect
			(at 1.800098 2.875026 270)
			(size 0.1778 0.6604)
			(layers "F.Cu" "F.Mask" "F.Paste")
			(net "SVID_ALERT_PVCCIN_CPU1_R")
		)
		(pad "24" smd rect
			(at 2.199894 2.875026 270)
			(size 0.1778 0.6604)
			(layers "F.Cu" "F.Mask" "F.Paste")
			(net "PVCCFA_EHV_FIVRA_CPU1_EN_R")
		)
		(pad "25" smd rect
			(at 2.875026 2.199894)
			(size 0.1778 0.6604)
			(layers "F.Cu" "F.Mask" "F.Paste")
			(net "SH_PVCCIN_CPU1_R")
		)
		(pad "26" smd rect
			(at 2.875026 1.800098)
			(size 0.1778 0.6604)
			(layers "F.Cu" "F.Mask" "F.Paste")
			(net "VSENSE_PVCCIN_CPU1_DN")
		)
		(pad "27" smd rect
			(at 2.875026 1.400048)
			(size 0.1778 0.6604)
			(layers "F.Cu" "F.Mask" "F.Paste")
			(net "PVCCIN_CPU1_IMON1")
		)
		(pad "28" smd rect
			(at 2.875026 0.999998)
			(size 0.1778 0.6604)
			(layers "F.Cu" "F.Mask" "F.Paste")
			(net "PVCCIN_CPU1_IMON2")
		)
		(pad "29" smd rect
			(at 2.875026 0.599948)
			(size 0.1778 0.6604)
			(layers "F.Cu" "F.Mask" "F.Paste")
			(net "PVCCIN_CPU1_IMON3")
		)
		(pad "30" smd rect
			(at 2.875026 0.199898)
			(size 0.1778 0.6604)
			(layers "F.Cu" "F.Mask" "F.Paste")
			(net "PVCCIN_CPU1_IMON4")
		)
		(pad "31" smd rect
			(at 2.875026 -0.199898)
			(size 0.1778 0.6604)
			(layers "F.Cu" "F.Mask" "F.Paste")
			(net "PVCCIN_CPU1_IMON5")
		)
		(pad "32" smd rect
			(at 2.875026 -0.599948)
			(size 0.1778 0.6604)
			(layers "F.Cu" "F.Mask" "F.Paste")
			(net "PVCCIN_CPU1_IMON6")
		)
		(pad "33" smd rect
			(at 2.875026 -0.999998)
			(size 0.1778 0.6604)
			(layers "F.Cu" "F.Mask" "F.Paste")
			(net "PVCCIN_CPU1_IMON7")
		)
		(pad "34" smd rect
			(at 2.875026 -1.400048)
			(size 0.1778 0.6604)
			(layers "F.Cu" "F.Mask" "F.Paste")
			(net "PVCCIN_CPU1_IMON8")
		)
		(pad "35" smd rect
			(at 2.875026 -1.800098)
			(size 0.1778 0.6604)
			(layers "F.Cu" "F.Mask" "F.Paste")
			(net "PVCCFA_EHV_FIVRA_CPU1_IMON4")
		)
		(pad "36" smd rect
			(at 2.875026 -2.199894)
			(size 0.1778 0.6604)
			(layers "F.Cu" "F.Mask" "F.Paste")
			(net "PVCCFA_EHV_FIVRA_CPU1_IMON3")
		)
		(pad "37" smd rect
			(at 2.199894 -2.875026 270)
			(size 0.1778 0.6604)
			(layers "F.Cu" "F.Mask" "F.Paste")
			(net "PVCCFA_EHV_FIVRA_CPU1_IMON2")
		)
		(pad "38" smd rect
			(at 1.800098 -2.875026 270)
			(size 0.1778 0.6604)
			(layers "F.Cu" "F.Mask" "F.Paste")
			(net "PVCCFA_EHV_FIVRA_CPU1_IMON1")
		)
		(pad "39" smd rect
			(at 1.400048 -2.875026 270)
			(size 0.1778 0.6604)
			(layers "F.Cu" "F.Mask" "F.Paste")
			(net "VSENSE_PVCCFA_EHV_FIVRA_CPU1_DN")
		)
		(pad "40" smd rect
			(at 0.999998 -2.875026 270)
			(size 0.1778 0.6604)
			(layers "F.Cu" "F.Mask" "F.Paste")
			(net "SH_PVCCFA_EHV_FIVRA_CPU1_R")
		)
		(pad "41" smd rect
			(at 0.599948 -2.875026 270)
			(size 0.1778 0.6604)
			(layers "F.Cu" "F.Mask" "F.Paste")
			(net "PVCCIN_CPU1_VR_FAULT")
		)
		(pad "42" smd rect
			(at 0.199898 -2.875026 270)
			(size 0.1778 0.6604)
			(layers "F.Cu" "F.Mask" "F.Paste")
			(net "PVCCIN_CPU1_ADDR")
		)
	)
)
